FILE_TYPE = MACRO_DRAWING;
SET COLOR_WIRE YELLOW;
SET COLOR_PROP ORANGE;
SET COLOR_DOT WHITE;
SET COLOR_ARC YELLOW;
SET COLOR_BODY GREEN;
SET COLOR_NOTE PURPLE;
SET PROP_DISPLAY VALUE;
SET PAGE_NUMBER P280;
FORCEADD Q_RES..2
R 2
(-6775 8600);
FORCEPROP 1 LAST PART_NUMBER CS28872FB01
J 2
(-6815 8475);
DISPLAY 0.617021 (-6815 8475);
PAINT BLUE (-6815 8475);
DISPLAY INVISIBLE (-6815 8475);
FORCEPROP 1 LAST VALUE 8.87K
J 2
(-6820 8675);
DISPLAY 0.617021 (-6820 8675);
PAINT SKYBLUE (-6820 8675);
FORCEPROP 1 LAST TOLERANCE 1%
J 2
(-6820 8625);
DISPLAY 0.617021 (-6820 8625);
PAINT SKYBLUE (-6820 8625);
FORCEPROP 1 LAST MATERIAL EMPTY
J 2
(-6815 8525);
DISPLAY 0.617021 (-6815 8525);
PAINT RED (-6815 8525);
FORCEPROP 1 LAST PACK_TYPE 0402LF
J 2
(-6815 8425);
DISPLAY 0.617021 (-6815 8425);
PAINT SKYBLUE (-6815 8425);
FORCEPROP 1 LAST WATTAGE 1/16W
J 2
(-6815 8575);
DISPLAY 0.617021 (-6815 8575);
PAINT SKYBLUE (-6815 8575);
FORCEPROP 1 LAST LOCATION PR1728
J 2
(-6820 8725);
DISPLAY 0.617021 (-6820 8725);
PAINT AQUA (-6820 8725);
FORCEPROP 1 LASTPIN (-6775 8700) $PN 1
J 2
(-6780 8662);
DISPLAY 0.617021 (-6780 8662);
PAINT MONO (-6780 8662);
FORCEPROP 1 LASTPIN (-6775 8500) $PN 2
J 2
(-6780 8510);
DISPLAY 0.617021 (-6780 8510);
PAINT MONO (-6780 8510);
FORCEPROP 1 LAST PATH I1
J 2
(-6825 8775);
DISPLAY 0.978723 (-6825 8775);
PAINT WHITE (-6825 8775);
DISPLAY INVISIBLE (-6825 8775);
FORCEPROP 2 LAST CDS_LIB pure_quanta
J 2
(-6775 8600);
DISPLAY INVISIBLE (-6775 8600);
FORCEPROP 0 LAST $SEC 1
J 0
(-6800 8750);
DISPLAY 0.680851 (-6800 8750);
PAINT MONO (-6800 8750);
DISPLAY INVISIBLE (-6800 8750);
FORCEPROP 0 LAST CDS_SEC 1
J 0
(-6800 8750);
DISPLAY 1.021277 (-6800 8750);
DISPLAY INVISIBLE (-6800 8750);
FORCEADD OFFPAGE..5
(-6025 9200);
FORCEPROP 2 LAST $XR0 292 
J 0
(-6310 9200);
DISPLAY 0.638298 (-6310 9200);
PAINT MONO (-6310 9200);
FORCEPROP 2 LAST PATH I10
J 0
(-6300 9250);
DISPLAY 1.021277 (-6300 9250);
DISPLAY INVISIBLE (-6300 9250);
FORCEPROP 2 LAST CDS_LIB standard
J 0
(-6025 9200);
DISPLAY INVISIBLE (-6025 9200);
FORCEPROP 1 LAST OFFPAGE TRUE
J 0
(-5700 9075);
DISPLAY 0.872340 (-5700 9075);
PAINT GREEN (-5700 9075);
DISPLAY INVISIBLE (-5700 9075);
FORCEPROP 1 LAST COMMENT_BODY TRUE
J 0
(-5925 9125);
DISPLAY 0.872340 (-5925 9125);
PAINT GREEN (-5925 9125);
DISPLAY INVISIBLE (-5925 9125);
FORCEADD Q_CAP..1
(-6100 9650);
FORCEPROP 1 LAST PART_NUMBER CH5222KEB01
J 0
(-6050 9475);
DISPLAY 0.617021 (-6050 9475);
PAINT BLUE (-6050 9475);
DISPLAY INVISIBLE (-6050 9475);
FORCEPROP 1 LAST TOLERANCE 10%
J 0
(-6050 9625);
DISPLAY 0.617021 (-6050 9625);
PAINT SKYBLUE (-6050 9625);
FORCEPROP 1 LAST VOLTAGE 10V
J 0
(-6050 9675);
DISPLAY 0.617021 (-6050 9675);
PAINT SKYBLUE (-6050 9675);
FORCEPROP 1 LAST VALUE 2.2UF
J 0
(-6050 9725);
DISPLAY 0.617021 (-6050 9725);
PAINT SKYBLUE (-6050 9725);
FORCEPROP 1 LAST MATERIAL X6S
J 0
(-6050 9575);
DISPLAY 0.617021 (-6050 9575);
PAINT SKYBLUE (-6050 9575);
FORCEPROP 1 LAST PACK_TYPE C0402
J 0
(-6050 9525);
DISPLAY 0.617021 (-6050 9525);
PAINT SKYBLUE (-6050 9525);
FORCEPROP 1 LAST LOCATION PC428
J 0
(-6050 9775);
DISPLAY 0.617021 (-6050 9775);
PAINT AQUA (-6050 9775);
FORCEPROP 1 LASTPIN (-6100 9750) $PN 1
J 0
(-6090 9730);
DISPLAY 0.617021 (-6090 9730);
PAINT MONO (-6090 9730);
FORCEPROP 1 LASTPIN (-6100 9550) $PN 2
J 0
(-6090 9530);
DISPLAY 0.617021 (-6090 9530);
PAINT MONO (-6090 9530);
FORCEPROP 1 LAST PATH I11
J 0
(-6050 9800);
DISPLAY 0.978723 (-6050 9800);
PAINT WHITE (-6050 9800);
DISPLAY INVISIBLE (-6050 9800);
FORCEPROP 2 LAST CDS_LIB pure_quanta
J 0
(-6100 9650);
DISPLAY INVISIBLE (-6100 9650);
FORCEPROP 1 LAST LOCATION PC428
J 0
(-6050 9825);
DISPLAY 1.021277 (-6050 9825);
PAINT AQUA (-6050 9825);
DISPLAY INVISIBLE (-6050 9825);
FORCEPROP 0 LAST $SEC 1
J 0
(-6050 9825);
DISPLAY 0.680851 (-6050 9825);
PAINT MONO (-6050 9825);
DISPLAY INVISIBLE (-6050 9825);
FORCEPROP 0 LAST CDS_SEC 1
J 0
(-6050 9825);
DISPLAY 1.021277 (-6050 9825);
DISPLAY INVISIBLE (-6050 9825);
FORCEADD UNIVERSAL_GND..1
(-6100 9400);
FORCEPROP 3 LASTPIN (-6100 9450) SIG_NAME GND\g
J 0
(-6090 9460);
DISPLAY 0.659574 (-6090 9460);
PAINT MONO (-6090 9460);
DISPLAY INVISIBLE (-6090 9460);
FORCEPROP 1 LAST PATH I12
J 0
(-6025 9400);
DISPLAY 0.872340 (-6025 9400);
PAINT AQUA (-6025 9400);
DISPLAY INVISIBLE (-6025 9400);
FORCEPROP 2 LAST CDS_LIB logical_power
J 0
(-6100 9400);
PAINT MONO (-6100 9400);
DISPLAY INVISIBLE (-6100 9400);
FORCEPROP 1 LAST HDL_POWER GND
J 1
(-6075 9325);
DISPLAY 0.872340 (-6075 9325);
PAINT GREEN (-6075 9325);
DISPLAY INVISIBLE (-6075 9325);
FORCEADD Q_RES..1
R 1
(-5650 9600);
FORCEPROP 1 LAST PART_NUMBER CS00002JB13
J 0
(-5575 9500);
DISPLAY 0.617021 (-5575 9500);
PAINT BLUE (-5575 9500);
DISPLAY INVISIBLE (-5575 9500);
FORCEPROP 1 LAST VALUE 0
J 2
(-5550 9650);
DISPLAY 0.617021 (-5550 9650);
PAINT SKYBLUE (-5550 9650);
FORCEPROP 1 LAST TOLERANCE 5%
J 0
(-5575 9600);
DISPLAY 0.617021 (-5575 9600);
PAINT SKYBLUE (-5575 9600);
FORCEPROP 1 LAST MATERIAL EMPTY
J 0
(-5575 9550);
DISPLAY 0.617021 (-5575 9550);
PAINT RED (-5575 9550);
FORCEPROP 1 LAST LOCATION PR4248
J 0
(-5575 9700);
DISPLAY 0.638298 (-5575 9700);
FORCEPROP 1 LASTPIN (-5650 9500) $PN 1
R 1
J 0
(-5662 9512);
DISPLAY 0.787234 (-5662 9512);
PAINT MONO (-5662 9512);
FORCEPROP 1 LASTPIN (-5650 9700) $PN 2
R 1
J 0
(-5662 9662);
DISPLAY 0.787234 (-5662 9662);
PAINT MONO (-5662 9662);
FORCEPROP 1 LAST PATH I13
R 1
J 0
(-5800 9550);
DISPLAY 0.978723 (-5800 9550);
PAINT WHITE (-5800 9550);
DISPLAY INVISIBLE (-5800 9550);
FORCEPROP 1 LAST PACK_TYPE 0402LF
R 1
J 0
(-5750 9550);
DISPLAY 0.404255 (-5750 9550);
PAINT SKYBLUE (-5750 9550);
DISPLAY INVISIBLE (-5750 9550);
FORCEPROP 1 LAST WATTAGE 1/16W
R 1
J 2
(-5725 9775);
DISPLAY 0.404255 (-5725 9775);
PAINT SKYBLUE (-5725 9775);
DISPLAY INVISIBLE (-5725 9775);
FORCEPROP 2 LAST CDS_LIB pure_quanta
R 1
J 0
(-5650 9600);
DISPLAY INVISIBLE (-5650 9600);
FORCEPROP 0 LAST $SEC 1
R 1
J 0
(-5575 9725);
DISPLAY 0.680851 (-5575 9725);
PAINT MONO (-5575 9725);
DISPLAY INVISIBLE (-5575 9725);
FORCEPROP 0 LAST CDS_SEC 1
R 1
J 0
(-5575 9725);
DISPLAY 1.021277 (-5575 9725);
DISPLAY INVISIBLE (-5575 9725);
FORCEADD RAA2213404GNPHB0..1
(-4600 9225);
FORCEPROP 1 LAST PART_NUMBER AL221340002
J 0
(-4870 10034);
DISPLAY 0.617021 (-4870 10034);
PAINT BLUE (-4870 10034);
DISPLAY INVISIBLE (-4870 10034);
FORCEPROP 2 LAST PART_TYPE SMLF
J 0
(-4875 10325);
DISPLAY 0.808511 (-4875 10325);
FORCEPROP 1 LAST MATERIAL IC
J 0
(-4870 9907);
DISPLAY 0.617021 (-4870 9907);
PAINT SKYBLUE (-4870 9907);
FORCEPROP 2 LAST VALUE RAA2213404GNP#HB0
J 0
(-4875 10270);
DISPLAY 0.617021 (-4875 10270);
PAINT SKYBLUE (-4875 10270);
FORCEPROP 1 LAST LOCATION PU49
J 0
(-4870 10181);
DISPLAY 0.617021 (-4870 10181);
PAINT AQUA (-4870 10181);
FORCEPROP 2 LASTPIN (-4175 9550) $PN 20
J 0
(-4165 9560);
DISPLAY 0.617021 (-4165 9560);
PAINT MONO (-4165 9560);
FORCEPROP 2 LASTPIN (-4175 8700) $PN 2
J 0
(-4165 8710);
DISPLAY 0.617021 (-4165 8710);
PAINT MONO (-4165 8710);
FORCEPROP 2 LASTPIN (-5025 8950) $PN 5
J 2
(-5035 8960);
DISPLAY 0.617021 (-5035 8960);
PAINT MONO (-5035 8960);
FORCEPROP 2 LASTPIN (-5025 8900) $PN 27
J 2
(-5035 8910);
DISPLAY 0.617021 (-5035 8910);
PAINT MONO (-5035 8910);
FORCEPROP 2 LASTPIN (-4175 8600) $PN 6_7-13_15-29
J 0
(-2765 8610);
DISPLAY 0.617021 (-2765 8610);
PAINT MONO (-2765 8610);
FORCEPROP 2 LASTPIN (-4175 8750) $PN 23
J 0
(-4165 8760);
DISPLAY 0.617021 (-4165 8760);
PAINT MONO (-4165 8760);
FORCEPROP 2 LASTPIN (-4175 8650) $PN 26
J 0
(-4165 8660);
DISPLAY 0.617021 (-4165 8660);
PAINT MONO (-4165 8660);
FORCEPROP 2 LASTPIN (-5025 9200) $PN 25
J 2
(-5035 9210);
DISPLAY 0.617021 (-5035 9210);
PAINT MONO (-5035 9210);
FORCEPROP 2 LASTPIN (-4175 8900) $PN 3
J 0
(-4165 8910);
DISPLAY 0.617021 (-4165 8910);
PAINT MONO (-4165 8910);
FORCEPROP 2 LASTPIN (-5025 9350) $PN 22
J 2
(-5035 9360);
DISPLAY 0.617021 (-5035 9360);
PAINT MONO (-5035 9360);
FORCEPROP 2 LASTPIN (-4175 9300) $PN 19
J 0
(-4165 9310);
DISPLAY 0.617021 (-4165 9310);
PAINT MONO (-4165 9310);
FORCEPROP 2 LASTPIN (-5025 8600) $PN 21
J 2
(-5035 8610);
DISPLAY 0.617021 (-5035 8610);
PAINT MONO (-5035 8610);
FORCEPROP 2 LASTPIN (-5025 9100) $PN 24
J 2
(-5035 9110);
DISPLAY 0.617021 (-5035 9110);
PAINT MONO (-5035 9110);
FORCEPROP 2 LASTPIN (-4175 9200) $PN 8_12
J 0
(-4165 9210);
DISPLAY 0.617021 (-4165 9210);
PAINT MONO (-4165 9210);
FORCEPROP 2 LASTPIN (-5025 8700) $PN 1
J 2
(-5035 8710);
DISPLAY 0.617021 (-5035 8710);
PAINT MONO (-5035 8710);
FORCEPROP 2 LASTPIN (-5025 9850) $PN 4
J 2
(-5035 9860);
DISPLAY 0.617021 (-5035 9860);
PAINT MONO (-5035 9860);
FORCEPROP 2 LASTPIN (-4175 9850) $PN 16_18-28
J 0
(-4165 9860);
DISPLAY 0.617021 (-4165 9860);
PAINT MONO (-4165 9860);
FORCEPROP 1 LAST PATH I14
J 0
(-4600 9225);
DISPLAY 0.723404 (-4600 9225);
PAINT GREEN (-4600 9225);
DISPLAY INVISIBLE (-4600 9225);
FORCEPROP 1 LAST NEEDS_NO_SIZE TRUE
J 0
(-4600 9225);
DISPLAY 0.723404 (-4600 9225);
PAINT GREEN (-4600 9225);
DISPLAY INVISIBLE (-4600 9225);
FORCEPROP 1 LAST CDS_LMAN_SYM_OUTLINE -275,675,275,-675
J 0
(-4600 9225);
DISPLAY 0.468085 (-4600 9225);
PAINT GREEN (-4600 9225);
DISPLAY INVISIBLE (-4600 9225);
FORCEPROP 2 LAST CDS_LIB pure_quanta
J 0
(-4600 9225);
DISPLAY INVISIBLE (-4600 9225);
FORCEPROP 2 LAST $SEC 1
J 0
(-4900 10275);
DISPLAY 0.680851 (-4900 10275);
PAINT MONO (-4900 10275);
DISPLAY INVISIBLE (-4900 10275);
FORCEPROP 2 LAST CDS_SEC 1
J 0
(-4850 10250);
DISPLAY 1.021277 (-4850 10250);
DISPLAY INVISIBLE (-4850 10250);
FORCEADD Q_RES..2
(-6100 10050);
FORCEPROP 1 LAST PART_NUMBER CS-2202FB01
J 0
(-6060 9925);
DISPLAY 0.617021 (-6060 9925);
PAINT BLUE (-6060 9925);
DISPLAY INVISIBLE (-6060 9925);
FORCEPROP 1 LAST PACK_TYPE 0402LF
J 0
(-6060 9875);
DISPLAY 0.617021 (-6060 9875);
PAINT SKYBLUE (-6060 9875);
FORCEPROP 1 LAST WATTAGE 1/16W
J 0
(-6060 10025);
DISPLAY 0.617021 (-6060 10025);
PAINT SKYBLUE (-6060 10025);
FORCEPROP 1 LAST VALUE 2.2
J 0
(-6055 10125);
DISPLAY 0.617021 (-6055 10125);
PAINT SKYBLUE (-6055 10125);
FORCEPROP 1 LAST TOLERANCE 1%
J 0
(-6055 10075);
DISPLAY 0.617021 (-6055 10075);
PAINT SKYBLUE (-6055 10075);
FORCEPROP 1 LAST MATERIAL CHIP
J 0
(-6060 9975);
DISPLAY 0.617021 (-6060 9975);
PAINT SKYBLUE (-6060 9975);
FORCEPROP 1 LAST LOCATION PR250
J 0
(-6055 10175);
DISPLAY 0.617021 (-6055 10175);
PAINT AQUA (-6055 10175);
FORCEPROP 1 LASTPIN (-6100 10150) $PN 1
J 0
(-6095 10112);
DISPLAY 0.617021 (-6095 10112);
PAINT MONO (-6095 10112);
FORCEPROP 1 LASTPIN (-6100 9950) $PN 2
J 0
(-6095 9960);
DISPLAY 0.617021 (-6095 9960);
PAINT MONO (-6095 9960);
FORCEPROP 1 LAST PATH I15
J 0
(-6050 10225);
DISPLAY 0.978723 (-6050 10225);
PAINT WHITE (-6050 10225);
DISPLAY INVISIBLE (-6050 10225);
FORCEPROP 2 LAST CDS_LIB pure_quanta
J 0
(-6100 10050);
DISPLAY INVISIBLE (-6100 10050);
FORCEPROP 1 LAST LOCATION PR250
J 0
(-6050 10225);
DISPLAY 1.021277 (-6050 10225);
PAINT AQUA (-6050 10225);
DISPLAY INVISIBLE (-6050 10225);
FORCEPROP 0 LAST $SEC 1
J 0
(-6050 10225);
DISPLAY 0.680851 (-6050 10225);
PAINT MONO (-6050 10225);
DISPLAY INVISIBLE (-6050 10225);
FORCEPROP 0 LAST CDS_SEC 1
J 0
(-6050 10225);
DISPLAY 1.021277 (-6050 10225);
DISPLAY INVISIBLE (-6050 10225);
FORCEADD Q_RES..2
(-5750 10675);
FORCEPROP 1 LAST PART_NUMBER CS00002JB13
J 0
(-5710 10550);
DISPLAY 0.617021 (-5710 10550);
PAINT BLUE (-5710 10550);
DISPLAY INVISIBLE (-5710 10550);
FORCEPROP 1 LAST PACK_TYPE 0402LF
J 0
(-5710 10500);
DISPLAY 0.617021 (-5710 10500);
PAINT SKYBLUE (-5710 10500);
FORCEPROP 1 LAST VALUE 0
J 0
(-5705 10750);
DISPLAY 0.617021 (-5705 10750);
PAINT SKYBLUE (-5705 10750);
FORCEPROP 1 LAST TOLERANCE 5%
J 0
(-5705 10700);
DISPLAY 0.617021 (-5705 10700);
PAINT SKYBLUE (-5705 10700);
FORCEPROP 1 LAST MATERIAL EMPTY
J 0
(-5710 10600);
DISPLAY 0.617021 (-5710 10600);
PAINT RED (-5710 10600);
FORCEPROP 1 LAST WATTAGE 1/16W
J 0
(-5710 10650);
DISPLAY 0.617021 (-5710 10650);
PAINT SKYBLUE (-5710 10650);
FORCEPROP 1 LAST LOCATION PR699
J 0
(-5705 10800);
DISPLAY 0.617021 (-5705 10800);
PAINT AQUA (-5705 10800);
FORCEPROP 1 LAST PATH I16
J 0
(-5700 10850);
DISPLAY 0.978723 (-5700 10850);
PAINT WHITE (-5700 10850);
DISPLAY INVISIBLE (-5700 10850);
FORCEPROP 2 LAST CDS_LIB pure_quanta
J 0
(-5750 10675);
DISPLAY INVISIBLE (-5750 10675);
FORCEPROP 0 LAST $SEC 1
J 0
(-5700 10850);
DISPLAY INVISIBLE (-5700 10850);
FORCEPROP 0 LAST CDS_SEC 1
J 0
(-5700 10850);
DISPLAY INVISIBLE (-5700 10850);
FORCEPROP 1 LASTPIN (-5750 10775) $PN 1
J 0
(-5745 10737);
DISPLAY 0.787234 (-5745 10737);
PAINT MONO (-5745 10737);
DISPLAY INVISIBLE (-5745 10737);
FORCEPROP 1 LASTPIN (-5750 10575) $PN 2
J 0
(-5745 10585);
DISPLAY 0.787234 (-5745 10585);
PAINT MONO (-5745 10585);
DISPLAY INVISIBLE (-5745 10585);
FORCEADD VCC15..1
(-5750 10900);
FORCEPROP 3 LASTPIN (-5750 10850) SIG_NAME P3V3\g
J 0
(-5740 10860);
DISPLAY 0.659574 (-5740 10860);
PAINT MONO (-5740 10860);
DISPLAY INVISIBLE (-5740 10860);
FORCEPROP 1 LAST HDL_POWER P3V3
J 1
(-5750 10950);
DISPLAY 0.617021 (-5750 10950);
PAINT GREEN (-5750 10950);
FORCEPROP 1 LAST PATH I17
J 0
(-5700 10925);
DISPLAY 0.872340 (-5700 10925);
PAINT AQUA (-5700 10925);
DISPLAY INVISIBLE (-5700 10925);
FORCEPROP 2 LAST CDS_LIB logical_power
J 0
(-5750 10900);
DISPLAY INVISIBLE (-5750 10900);
FORCEADD Q_RES..1
(-3125 8700);
FORCEPROP 1 LAST PART_NUMBER CS00002JB13
J 0
(-3025 8650);
DISPLAY 0.638298 (-3025 8650);
DISPLAY INVISIBLE (-3025 8650);
FORCEPROP 1 LAST WATTAGE 1/16W
J 2
(-2550 8700);
DISPLAY 0.638298 (-2550 8700);
FORCEPROP 1 LAST TOLERANCE 5%
J 0
(-2975 8700);
DISPLAY 0.638298 (-2975 8700);
FORCEPROP 1 LAST VALUE 0
J 2
(-3000 8700);
DISPLAY 0.638298 (-3000 8700);
FORCEPROP 1 LAST PACK_TYPE 0402LF
J 0
(-2900 8700);
DISPLAY 0.638298 (-2900 8700);
FORCEPROP 1 LAST MATERIAL EMPTY
J 0
(-3325 8650);
DISPLAY 0.638298 (-3325 8650);
PAINT RED (-3325 8650);
FORCEPROP 1 LAST LOCATION PR4249
J 0
(-3350 8700);
DISPLAY 0.638298 (-3350 8700);
FORCEPROP 1 LASTPIN (-3225 8700) $PN 1
J 0
(-3213 8712);
DISPLAY 0.787234 (-3213 8712);
PAINT MONO (-3213 8712);
FORCEPROP 1 LASTPIN (-3025 8700) $PN 2
J 0
(-3063 8712);
DISPLAY 0.787234 (-3063 8712);
PAINT MONO (-3063 8712);
FORCEPROP 1 LAST PATH I18
J 0
(-3175 8850);
DISPLAY 0.978723 (-3175 8850);
PAINT WHITE (-3175 8850);
DISPLAY INVISIBLE (-3175 8850);
FORCEPROP 2 LAST CDS_LIB pure_quanta
J 0
(-3125 8700);
DISPLAY INVISIBLE (-3125 8700);
FORCEPROP 0 LAST $SEC 1
J 0
(-2550 8750);
DISPLAY 0.680851 (-2550 8750);
PAINT MONO (-2550 8750);
DISPLAY INVISIBLE (-2550 8750);
FORCEPROP 0 LAST CDS_SEC 1
J 0
(-2550 8750);
DISPLAY 1.021277 (-2550 8750);
DISPLAY INVISIBLE (-2550 8750);
FORCEADD UNIVERSAL_GND..1
(-2525 8475);
FORCEPROP 3 LASTPIN (-2525 8525) SIG_NAME GND\g
J 0
(-2515 8535);
DISPLAY 0.659574 (-2515 8535);
PAINT MONO (-2515 8535);
DISPLAY INVISIBLE (-2515 8535);
FORCEPROP 1 LAST PATH I19
J 0
(-2450 8475);
DISPLAY 0.872340 (-2450 8475);
PAINT AQUA (-2450 8475);
DISPLAY INVISIBLE (-2450 8475);
FORCEPROP 2 LAST CDS_LIB logical_power
J 0
(-2525 8475);
PAINT MONO (-2525 8475);
DISPLAY INVISIBLE (-2525 8475);
FORCEPROP 1 LAST HDL_POWER GND
J 1
(-2500 8400);
DISPLAY 0.872340 (-2500 8400);
PAINT GREEN (-2500 8400);
DISPLAY INVISIBLE (-2500 8400);
FORCEADD UNIVERSAL_GND..1
(-6775 8375);
FORCEPROP 3 LASTPIN (-6775 8425) SIG_NAME GND\g
J 0
(-6765 8435);
DISPLAY 0.659574 (-6765 8435);
PAINT MONO (-6765 8435);
DISPLAY INVISIBLE (-6765 8435);
FORCEPROP 1 LAST PATH I2
J 0
(-6700 8375);
DISPLAY 0.872340 (-6700 8375);
PAINT AQUA (-6700 8375);
DISPLAY INVISIBLE (-6700 8375);
FORCEPROP 2 LAST CDS_LIB logical_power
J 0
(-6775 8375);
DISPLAY INVISIBLE (-6775 8375);
FORCEPROP 1 LAST HDL_POWER GND
J 1
(-6750 8300);
DISPLAY 0.872340 (-6750 8300);
PAINT GREEN (-6750 8300);
DISPLAY INVISIBLE (-6750 8300);
FORCEADD Q_RES..1
(-3025 8900);
FORCEPROP 1 LAST PART_NUMBER CS00002JB13
J 0
(-3125 8950);
DISPLAY 0.617021 (-3125 8950);
PAINT BLUE (-3125 8950);
DISPLAY INVISIBLE (-3125 8950);
FORCEPROP 1 LAST VALUE 0
J 2
(-2900 8900);
DISPLAY 0.617021 (-2900 8900);
PAINT SKYBLUE (-2900 8900);
FORCEPROP 1 LAST PACK_TYPE 0402LF
J 0
(-3125 8975);
DISPLAY 0.617021 (-3125 8975);
PAINT SKYBLUE (-3125 8975);
FORCEPROP 1 LAST TOLERANCE 5%
J 0
(-2875 8900);
DISPLAY 0.617021 (-2875 8900);
PAINT SKYBLUE (-2875 8900);
FORCEPROP 1 LAST WATTAGE 1/16W
J 2
(-2775 8975);
DISPLAY 0.617021 (-2775 8975);
PAINT SKYBLUE (-2775 8975);
FORCEPROP 1 LAST MATERIAL CHIP
J 0
(-3125 9000);
DISPLAY 0.617021 (-3125 9000);
PAINT SKYBLUE (-3125 9000);
FORCEPROP 1 LAST LOCATION PR1799
J 0
(-3275 8900);
DISPLAY 0.617021 (-3275 8900);
PAINT AQUA (-3275 8900);
FORCEPROP 1 LASTPIN (-3125 8900) $PN 1
J 0
(-3113 8912);
DISPLAY 0.617021 (-3113 8912);
FORCEPROP 1 LASTPIN (-2925 8900) $PN 2
J 0
(-2963 8912);
DISPLAY 0.617021 (-2963 8912);
FORCEPROP 1 LAST PATH I20
J 0
(-3075 9050);
DISPLAY 0.978723 (-3075 9050);
PAINT WHITE (-3075 9050);
DISPLAY INVISIBLE (-3075 9050);
FORCEPROP 2 LAST CDS_LIB pure_quanta
J 0
(-3025 8900);
PAINT MONO (-3025 8900);
DISPLAY INVISIBLE (-3025 8900);
FORCEPROP 2 LAST $SEC 1
J 0
(-3075 9100);
DISPLAY 0.680851 (-3075 9100);
PAINT MONO (-3075 9100);
DISPLAY INVISIBLE (-3075 9100);
FORCEPROP 2 LAST CDS_SEC 1
J 0
(-3075 9100);
DISPLAY 1.021277 (-3075 9100);
DISPLAY INVISIBLE (-3075 9100);
FORCEADD VCC15..1
(-2600 9050);
FORCEPROP 3 LASTPIN (-2600 9000) SIG_NAME PVCCFA_EHV_CPU1_VDD1\g
J 0
(-2590 9010);
DISPLAY 0.659574 (-2590 9010);
PAINT MONO (-2590 9010);
DISPLAY INVISIBLE (-2590 9010);
FORCEPROP 1 LAST HDL_POWER PVCCFA_EHV_CPU1_VDD1
J 1
(-2550 9100);
DISPLAY 0.617021 (-2550 9100);
PAINT GREEN (-2550 9100);
FORCEPROP 1 LAST PATH I21
J 0
(-2550 9075);
DISPLAY 0.872340 (-2550 9075);
PAINT AQUA (-2550 9075);
DISPLAY INVISIBLE (-2550 9075);
FORCEPROP 2 LAST CDS_LIB logical_power
J 0
(-2600 9050);
PAINT MONO (-2600 9050);
DISPLAY INVISIBLE (-2600 9050);
FORCEADD Q_CAP..1
R 2
(-2450 9475);
FORCEPROP 1 LAST PART_NUMBER CH4106K1B01
J 2
(-2500 9425);
DISPLAY 0.617021 (-2500 9425);
PAINT BLUE (-2500 9425);
DISPLAY INVISIBLE (-2500 9425);
FORCEPROP 1 LAST VOLTAGE 50V
J 2
(-2500 9500);
DISPLAY 0.617021 (-2500 9500);
PAINT SKYBLUE (-2500 9500);
FORCEPROP 1 LAST TOLERANCE 10%
J 2
(-2500 9475);
DISPLAY 0.617021 (-2500 9475);
PAINT SKYBLUE (-2500 9475);
FORCEPROP 1 LAST MATERIAL X7R
J 2
(-2500 9450);
DISPLAY 0.617021 (-2500 9450);
PAINT SKYBLUE (-2500 9450);
FORCEPROP 1 LAST VALUE 100NF
J 2
(-2500 9525);
DISPLAY 0.617021 (-2500 9525);
PAINT SKYBLUE (-2500 9525);
FORCEPROP 1 LAST PACK_TYPE C0402
J 2
(-2500 9400);
DISPLAY 0.617021 (-2500 9400);
PAINT SKYBLUE (-2500 9400);
FORCEPROP 1 LAST LOCATION PC431
J 2
(-2500 9550);
DISPLAY 0.617021 (-2500 9550);
PAINT AQUA (-2500 9550);
FORCEPROP 1 LASTPIN (-2450 9575) $PN 1
J 2
(-2460 9555);
DISPLAY 0.617021 (-2460 9555);
FORCEPROP 1 LASTPIN (-2450 9375) $PN 2
J 2
(-2460 9355);
DISPLAY 0.617021 (-2460 9355);
FORCEPROP 1 LAST PATH I22
J 2
(-2500 9625);
DISPLAY 0.978723 (-2500 9625);
PAINT WHITE (-2500 9625);
DISPLAY INVISIBLE (-2500 9625);
FORCEPROP 2 LAST CDS_LIB pure_quanta
J 2
(-2450 9475);
PAINT MONO (-2450 9475);
DISPLAY INVISIBLE (-2450 9475);
FORCEPROP 2 LAST $SEC 1
J 0
(-2500 9675);
DISPLAY 0.680851 (-2500 9675);
PAINT MONO (-2500 9675);
DISPLAY INVISIBLE (-2500 9675);
FORCEPROP 2 LAST CDS_SEC 1
J 0
(-2500 9675);
DISPLAY 1.021277 (-2500 9675);
DISPLAY INVISIBLE (-2500 9675);
FORCEADD Q_INDUCTOR..1
(-2225 9225);
FORCEPROP 1 LAST PART_NUMBER CV+30Y0KZ05
J 0
(-2350 9335);
DISPLAY 0.617021 (-2350 9335);
PAINT BLUE (-2350 9335);
DISPLAY INVISIBLE (-2350 9335);
FORCEPROP 1 LAST MATERIAL IND
J 0
(-2350 9280);
DISPLAY 0.617021 (-2350 9280);
PAINT SKYBLUE (-2350 9280);
FORCEPROP 2 LAST PACK_TYPE SMLF
J 0
(-2350 9425);
DISPLAY 0.617021 (-2350 9425);
PAINT SKYBLUE (-2350 9425);
FORCEPROP 2 LAST VALUE 300NH/33A
J 0
(-2350 9475);
DISPLAY 0.617021 (-2350 9475);
PAINT SKYBLUE (-2350 9475);
FORCEPROP 1 LAST LOCATION PL20
J 0
(-2350 9385);
DISPLAY 0.617021 (-2350 9385);
PAINT AQUA (-2350 9385);
FORCEPROP 0 LASTPIN (-2325 9200) $PN 1
J 2
(-2335 9210);
DISPLAY 0.617021 (-2335 9210);
PAINT MONO (-2335 9210);
FORCEPROP 0 LASTPIN (-2125 9200) $PN 2
J 0
(-2115 9210);
DISPLAY 0.617021 (-2115 9210);
PAINT MONO (-2115 9210);
FORCEPROP 1 LAST PATH I23
J 0
(-2150 9280);
DISPLAY 0.723404 (-2150 9280);
PAINT GREEN (-2150 9280);
DISPLAY INVISIBLE (-2150 9280);
FORCEPROP 1 LAST NEEDS_NO_SIZE TRUE
J 0
(-2225 9225);
DISPLAY 0.468085 (-2225 9225);
PAINT GREEN (-2225 9225);
DISPLAY INVISIBLE (-2225 9225);
FORCEPROP 2 LAST CDS_LIB pure_quanta
J 0
(-2225 9225);
DISPLAY INVISIBLE (-2225 9225);
FORCEPROP 0 LAST $SEC 1
J 0
(-2350 9525);
DISPLAY 0.680851 (-2350 9525);
PAINT MONO (-2350 9525);
DISPLAY INVISIBLE (-2350 9525);
FORCEPROP 0 LAST CDS_SEC 1
J 0
(-2350 9525);
DISPLAY 1.021277 (-2350 9525);
DISPLAY INVISIBLE (-2350 9525);
FORCEADD Q_CAP..1
(-3775 10100);
FORCEPROP 1 LAST PART_NUMBER TMP_QCH2336K1B12
J 0
(-3725 9950);
DISPLAY 0.489362 (-3725 9950);
PAINT BLUE (-3725 9950);
DISPLAY INVISIBLE (-3725 9950);
FORCEPROP 1 LAST VOLTAGE 50V
J 0
(-3725 10150);
DISPLAY 0.617021 (-3725 10150);
PAINT SKYBLUE (-3725 10150);
FORCEPROP 1 LAST VALUE 3300PF
J 0
(-3725 10200);
DISPLAY 0.617021 (-3725 10200);
PAINT SKYBLUE (-3725 10200);
FORCEPROP 1 LAST TOLERANCE 10%
J 0
(-3725 10100);
DISPLAY 0.617021 (-3725 10100);
PAINT SKYBLUE (-3725 10100);
FORCEPROP 1 LAST MATERIAL X7R
J 0
(-3725 10050);
DISPLAY 0.617021 (-3725 10050);
PAINT SKYBLUE (-3725 10050);
FORCEPROP 1 LAST PACK_TYPE 0402
J 0
(-3725 10000);
DISPLAY 0.617021 (-3725 10000);
PAINT SKYBLUE (-3725 10000);
FORCEPROP 1 LAST LOCATION PC429
J 0
(-3725 10250);
DISPLAY 0.617021 (-3725 10250);
PAINT AQUA (-3725 10250);
FORCEPROP 1 LASTPIN (-3775 10200) $PN 1
J 0
(-3765 10180);
DISPLAY 0.617021 (-3765 10180);
PAINT MONO (-3765 10180);
FORCEPROP 1 LASTPIN (-3775 10000) $PN 2
J 0
(-3765 9980);
DISPLAY 0.617021 (-3765 9980);
PAINT MONO (-3765 9980);
FORCEPROP 1 LAST PATH I24
J 0
(-3725 10250);
DISPLAY 0.978723 (-3725 10250);
PAINT WHITE (-3725 10250);
DISPLAY INVISIBLE (-3725 10250);
FORCEPROP 2 LAST CDS_LIB pure_quanta
J 0
(-3775 10100);
DISPLAY INVISIBLE (-3775 10100);
FORCEPROP 1 LAST LOCATION PC429
J 0
(-3725 10300);
DISPLAY 1.021277 (-3725 10300);
PAINT AQUA (-3725 10300);
DISPLAY INVISIBLE (-3725 10300);
FORCEPROP 0 LAST $SEC 1
J 0
(-3725 10300);
DISPLAY 0.680851 (-3725 10300);
PAINT MONO (-3725 10300);
DISPLAY INVISIBLE (-3725 10300);
FORCEPROP 0 LAST CDS_SEC 1
J 0
(-3725 10300);
DISPLAY 1.021277 (-3725 10300);
DISPLAY INVISIBLE (-3725 10300);
FORCEADD Q_RES..1
(-3250 9650);
FORCEPROP 1 LAST PART_NUMBER CS-3302FB01
J 0
(-3350 9700);
DISPLAY 0.617021 (-3350 9700);
PAINT BLUE (-3350 9700);
DISPLAY INVISIBLE (-3350 9700);
FORCEPROP 1 LAST TOLERANCE 1%
J 0
(-3050 9650);
DISPLAY 0.617021 (-3050 9650);
PAINT SKYBLUE (-3050 9650);
FORCEPROP 1 LAST WATTAGE 1/16W
J 2
(-2975 9725);
DISPLAY 0.617021 (-2975 9725);
PAINT SKYBLUE (-2975 9725);
FORCEPROP 1 LAST PACK_TYPE 0402LF
J 0
(-3350 9725);
DISPLAY 0.617021 (-3350 9725);
PAINT SKYBLUE (-3350 9725);
FORCEPROP 1 LAST MATERIAL CHIP
J 0
(-3350 9750);
DISPLAY 0.617021 (-3350 9750);
PAINT SKYBLUE (-3350 9750);
FORCEPROP 1 LAST VALUE 3.3
J 2
(-3075 9650);
DISPLAY 0.617021 (-3075 9650);
PAINT SKYBLUE (-3075 9650);
FORCEPROP 1 LAST LOCATION PR1798
J 0
(-3475 9650);
DISPLAY 0.617021 (-3475 9650);
PAINT AQUA (-3475 9650);
FORCEPROP 1 LASTPIN (-3350 9650) $PN 1
J 0
(-3338 9662);
DISPLAY 0.617021 (-3338 9662);
FORCEPROP 1 LASTPIN (-3150 9650) $PN 2
J 0
(-3188 9662);
DISPLAY 0.617021 (-3188 9662);
FORCEPROP 1 LAST PATH I25
J 0
(-3300 9800);
DISPLAY 0.978723 (-3300 9800);
PAINT WHITE (-3300 9800);
DISPLAY INVISIBLE (-3300 9800);
FORCEPROP 2 LAST CDS_LIB pure_quanta
J 0
(-3250 9650);
PAINT MONO (-3250 9650);
DISPLAY INVISIBLE (-3250 9650);
FORCEPROP 2 LAST $SEC 1
J 0
(-3300 9850);
DISPLAY 0.680851 (-3300 9850);
PAINT MONO (-3300 9850);
DISPLAY INVISIBLE (-3300 9850);
FORCEPROP 2 LAST CDS_SEC 1
J 0
(-3300 9850);
DISPLAY 1.021277 (-3300 9850);
DISPLAY INVISIBLE (-3300 9850);
FORCEADD Q_CAP..1
(-3325 10100);
FORCEPROP 1 LAST PART_NUMBER CH5103KEB01
J 0
(-3275 9950);
DISPLAY 0.489362 (-3275 9950);
PAINT BLUE (-3275 9950);
DISPLAY INVISIBLE (-3275 9950);
FORCEPROP 1 LAST MATERIAL X6S
J 0
(-3275 10050);
DISPLAY 0.617021 (-3275 10050);
PAINT SKYBLUE (-3275 10050);
FORCEPROP 1 LAST TOLERANCE 10%
J 0
(-3275 10100);
DISPLAY 0.617021 (-3275 10100);
PAINT SKYBLUE (-3275 10100);
FORCEPROP 1 LAST VOLTAGE 16V
J 0
(-3275 10150);
DISPLAY 0.617021 (-3275 10150);
PAINT SKYBLUE (-3275 10150);
FORCEPROP 1 LAST PACK_TYPE C0402
J 0
(-3275 10000);
DISPLAY 0.617021 (-3275 10000);
PAINT SKYBLUE (-3275 10000);
FORCEPROP 1 LAST VALUE 1UF
J 0
(-3275 10200);
DISPLAY 0.617021 (-3275 10200);
PAINT SKYBLUE (-3275 10200);
FORCEPROP 1 LAST LOCATION PC430
J 0
(-3275 10250);
DISPLAY 0.617021 (-3275 10250);
PAINT AQUA (-3275 10250);
FORCEPROP 1 LASTPIN (-3325 10200) $PN 1
J 0
(-3315 10180);
DISPLAY 0.617021 (-3315 10180);
PAINT MONO (-3315 10180);
FORCEPROP 1 LASTPIN (-3325 10000) $PN 2
J 0
(-3315 9980);
DISPLAY 0.617021 (-3315 9980);
PAINT MONO (-3315 9980);
FORCEPROP 1 LAST PATH I26
J 0
(-3275 10250);
DISPLAY 0.978723 (-3275 10250);
PAINT WHITE (-3275 10250);
DISPLAY INVISIBLE (-3275 10250);
FORCEPROP 2 LAST CDS_LIB pure_quanta
J 0
(-3325 10100);
DISPLAY INVISIBLE (-3325 10100);
FORCEPROP 1 LAST LOCATION PC430
J 0
(-3275 10300);
DISPLAY 1.021277 (-3275 10300);
PAINT AQUA (-3275 10300);
DISPLAY INVISIBLE (-3275 10300);
FORCEPROP 0 LAST $SEC 1
J 0
(-3275 10300);
DISPLAY 0.680851 (-3275 10300);
PAINT MONO (-3275 10300);
DISPLAY INVISIBLE (-3275 10300);
FORCEPROP 0 LAST CDS_SEC 1
J 0
(-3275 10300);
DISPLAY 1.021277 (-3275 10300);
DISPLAY INVISIBLE (-3275 10300);
FORCEADD Q_CAP..1
(-2950 10100);
FORCEPROP 1 LAST PART_NUMBER CH6223MEA01
J 0
(-2900 9950);
DISPLAY 0.489362 (-2900 9950);
PAINT BLUE (-2900 9950);
DISPLAY INVISIBLE (-2900 9950);
FORCEPROP 1 LAST VALUE 22UF
J 0
(-2900 10200);
DISPLAY 0.617021 (-2900 10200);
PAINT SKYBLUE (-2900 10200);
FORCEPROP 1 LAST PACK_TYPE C0805
J 0
(-2900 10000);
DISPLAY 0.617021 (-2900 10000);
PAINT SKYBLUE (-2900 10000);
FORCEPROP 1 LAST MATERIAL X6S
J 0
(-2900 10050);
DISPLAY 0.617021 (-2900 10050);
PAINT SKYBLUE (-2900 10050);
FORCEPROP 1 LAST VOLTAGE 16V
J 0
(-2900 10150);
DISPLAY 0.617021 (-2900 10150);
PAINT SKYBLUE (-2900 10150);
FORCEPROP 1 LAST TOLERANCE 20%
J 0
(-2900 10100);
DISPLAY 0.617021 (-2900 10100);
PAINT SKYBLUE (-2900 10100);
FORCEPROP 1 LAST LOCATION PC432
J 0
(-2900 10250);
DISPLAY 0.617021 (-2900 10250);
PAINT AQUA (-2900 10250);
FORCEPROP 1 LASTPIN (-2950 10200) $PN 1
J 0
(-2940 10180);
DISPLAY 0.617021 (-2940 10180);
PAINT MONO (-2940 10180);
FORCEPROP 1 LASTPIN (-2950 10000) $PN 2
J 0
(-2940 9980);
DISPLAY 0.617021 (-2940 9980);
PAINT MONO (-2940 9980);
FORCEPROP 1 LAST PATH I27
J 0
(-2900 10250);
DISPLAY 0.978723 (-2900 10250);
PAINT WHITE (-2900 10250);
DISPLAY INVISIBLE (-2900 10250);
FORCEPROP 2 LAST CDS_LIB pure_quanta
J 0
(-2950 10100);
DISPLAY INVISIBLE (-2950 10100);
FORCEPROP 1 LAST LOCATION PC432
J 0
(-2900 10300);
DISPLAY 1.021277 (-2900 10300);
PAINT AQUA (-2900 10300);
DISPLAY INVISIBLE (-2900 10300);
FORCEPROP 0 LAST $SEC 1
J 0
(-2900 10300);
DISPLAY 0.680851 (-2900 10300);
PAINT MONO (-2900 10300);
DISPLAY INVISIBLE (-2900 10300);
FORCEPROP 0 LAST CDS_SEC 1
J 0
(-2900 10300);
DISPLAY 1.021277 (-2900 10300);
DISPLAY INVISIBLE (-2900 10300);
FORCEADD Q_CAP..1
(-2575 10100);
FORCEPROP 1 LAST PART_NUMBER CH6223MEA01
J 0
(-2525 9950);
DISPLAY 0.489362 (-2525 9950);
PAINT BLUE (-2525 9950);
DISPLAY INVISIBLE (-2525 9950);
FORCEPROP 1 LAST PACK_TYPE C0805
J 0
(-2525 10000);
DISPLAY 0.617021 (-2525 10000);
PAINT SKYBLUE (-2525 10000);
FORCEPROP 1 LAST VOLTAGE 16V
J 0
(-2525 10150);
DISPLAY 0.617021 (-2525 10150);
PAINT SKYBLUE (-2525 10150);
FORCEPROP 1 LAST VALUE 22UF
J 0
(-2525 10200);
DISPLAY 0.617021 (-2525 10200);
PAINT SKYBLUE (-2525 10200);
FORCEPROP 1 LAST MATERIAL X6S
J 0
(-2525 10050);
DISPLAY 0.617021 (-2525 10050);
PAINT SKYBLUE (-2525 10050);
FORCEPROP 1 LAST TOLERANCE 20%
J 0
(-2525 10100);
DISPLAY 0.617021 (-2525 10100);
PAINT SKYBLUE (-2525 10100);
FORCEPROP 1 LAST LOCATION PC433
J 0
(-2525 10250);
DISPLAY 0.617021 (-2525 10250);
PAINT AQUA (-2525 10250);
FORCEPROP 1 LASTPIN (-2575 10200) $PN 1
J 0
(-2565 10180);
DISPLAY 0.617021 (-2565 10180);
PAINT MONO (-2565 10180);
FORCEPROP 1 LASTPIN (-2575 10000) $PN 2
J 0
(-2565 9980);
DISPLAY 0.617021 (-2565 9980);
PAINT MONO (-2565 9980);
FORCEPROP 1 LAST PATH I28
J 0
(-2525 10250);
DISPLAY 0.978723 (-2525 10250);
PAINT WHITE (-2525 10250);
DISPLAY INVISIBLE (-2525 10250);
FORCEPROP 2 LAST CDS_LIB pure_quanta
J 0
(-2575 10100);
DISPLAY INVISIBLE (-2575 10100);
FORCEPROP 1 LAST LOCATION PC433
J 0
(-2525 10300);
DISPLAY 1.021277 (-2525 10300);
PAINT AQUA (-2525 10300);
DISPLAY INVISIBLE (-2525 10300);
FORCEPROP 0 LAST $SEC 1
J 0
(-2525 10300);
DISPLAY 0.680851 (-2525 10300);
PAINT MONO (-2525 10300);
DISPLAY INVISIBLE (-2525 10300);
FORCEPROP 0 LAST CDS_SEC 1
J 0
(-2525 10300);
DISPLAY 1.021277 (-2525 10300);
DISPLAY INVISIBLE (-2525 10300);
FORCEADD Q_CAP..1
(-2000 9000);
FORCEPROP 1 LAST PART_NUMBER CH4106K1B01
J 0
(-1950 8825);
DISPLAY 0.617021 (-1950 8825);
PAINT BLUE (-1950 8825);
DISPLAY INVISIBLE (-1950 8825);
FORCEPROP 1 LAST TOLERANCE 10%
J 0
(-1950 8975);
DISPLAY 0.617021 (-1950 8975);
PAINT SKYBLUE (-1950 8975);
FORCEPROP 1 LAST MATERIAL X7R
J 0
(-1950 8925);
DISPLAY 0.617021 (-1950 8925);
PAINT SKYBLUE (-1950 8925);
FORCEPROP 1 LAST VALUE 100NF
J 0
(-1950 9075);
DISPLAY 0.617021 (-1950 9075);
PAINT SKYBLUE (-1950 9075);
FORCEPROP 1 LAST VOLTAGE 50V
J 0
(-1950 9025);
DISPLAY 0.617021 (-1950 9025);
PAINT SKYBLUE (-1950 9025);
FORCEPROP 1 LAST PACK_TYPE C0402
J 0
(-1950 8875);
DISPLAY 0.617021 (-1950 8875);
PAINT SKYBLUE (-1950 8875);
FORCEPROP 1 LAST LOCATION PC434
J 0
(-1950 9125);
DISPLAY 0.617021 (-1950 9125);
PAINT AQUA (-1950 9125);
FORCEPROP 1 LASTPIN (-2000 9100) $PN 1
J 0
(-1990 9080);
DISPLAY 0.617021 (-1990 9080);
PAINT MONO (-1990 9080);
FORCEPROP 1 LASTPIN (-2000 8900) $PN 2
J 0
(-1990 8880);
DISPLAY 0.617021 (-1990 8880);
PAINT MONO (-1990 8880);
FORCEPROP 1 LAST PATH I29
J 0
(-1950 9150);
DISPLAY 0.978723 (-1950 9150);
PAINT WHITE (-1950 9150);
DISPLAY INVISIBLE (-1950 9150);
FORCEPROP 2 LAST CDS_LIB pure_quanta
J 0
(-2000 9000);
DISPLAY INVISIBLE (-2000 9000);
FORCEPROP 1 LAST LOCATION PC434
J 0
(-1950 9175);
DISPLAY 1.021277 (-1950 9175);
PAINT AQUA (-1950 9175);
DISPLAY INVISIBLE (-1950 9175);
FORCEPROP 0 LAST $SEC 1
J 0
(-1950 9175);
DISPLAY 0.680851 (-1950 9175);
PAINT MONO (-1950 9175);
DISPLAY INVISIBLE (-1950 9175);
FORCEPROP 0 LAST CDS_SEC 1
J 0
(-1950 9175);
DISPLAY 1.021277 (-1950 9175);
DISPLAY INVISIBLE (-1950 9175);
FORCEADD UNIVERSAL_GND..1
(-7025 8925);
FORCEPROP 3 LASTPIN (-7025 8975) SIG_NAME GND\g
J 0
(-7015 8985);
DISPLAY 0.659574 (-7015 8985);
PAINT MONO (-7015 8985);
DISPLAY INVISIBLE (-7015 8985);
FORCEPROP 1 LAST PATH I3
J 0
(-6950 8925);
DISPLAY 0.872340 (-6950 8925);
PAINT AQUA (-6950 8925);
DISPLAY INVISIBLE (-6950 8925);
FORCEPROP 2 LAST CDS_LIB logical_power
J 0
(-7025 8925);
PAINT MONO (-7025 8925);
DISPLAY INVISIBLE (-7025 8925);
FORCEPROP 1 LAST HDL_POWER GND
J 1
(-7000 8850);
DISPLAY 0.872340 (-7000 8850);
PAINT GREEN (-7000 8850);
DISPLAY INVISIBLE (-7000 8850);
FORCEADD Q_CAP..1
(-1600 9000);
FORCEPROP 1 LAST PART_NUMBER CH622KMEA03
J 0
(-1550 8825);
DISPLAY 0.617021 (-1550 8825);
PAINT BLUE (-1550 8825);
DISPLAY INVISIBLE (-1550 8825);
FORCEPROP 1 LAST VALUE 22UF
J 0
(-1550 9075);
DISPLAY 0.617021 (-1550 9075);
PAINT SKYBLUE (-1550 9075);
FORCEPROP 1 LAST VOLTAGE 4V
J 0
(-1550 9025);
DISPLAY 0.617021 (-1550 9025);
PAINT SKYBLUE (-1550 9025);
FORCEPROP 1 LAST MATERIAL X6S
J 0
(-1550 8925);
DISPLAY 0.617021 (-1550 8925);
PAINT SKYBLUE (-1550 8925);
FORCEPROP 1 LAST PACK_TYPE C0805
J 0
(-1550 8875);
DISPLAY 0.617021 (-1550 8875);
PAINT SKYBLUE (-1550 8875);
FORCEPROP 1 LAST TOLERANCE 20%
J 0
(-1550 8975);
DISPLAY 0.617021 (-1550 8975);
PAINT SKYBLUE (-1550 8975);
FORCEPROP 1 LAST LOCATION PC435
J 0
(-1550 9125);
DISPLAY 0.617021 (-1550 9125);
PAINT AQUA (-1550 9125);
FORCEPROP 1 LASTPIN (-1600 9100) $PN 1
J 0
(-1590 9080);
DISPLAY 0.617021 (-1590 9080);
PAINT MONO (-1590 9080);
FORCEPROP 1 LASTPIN (-1600 8900) $PN 2
J 0
(-1590 8880);
DISPLAY 0.617021 (-1590 8880);
PAINT MONO (-1590 8880);
FORCEPROP 1 LAST PATH I30
J 0
(-1550 9150);
DISPLAY 0.978723 (-1550 9150);
PAINT WHITE (-1550 9150);
DISPLAY INVISIBLE (-1550 9150);
FORCEPROP 2 LAST CDS_LIB pure_quanta
J 0
(-1600 9000);
DISPLAY INVISIBLE (-1600 9000);
FORCEPROP 1 LAST LOCATION PC435
J 0
(-1550 9175);
DISPLAY 1.021277 (-1550 9175);
PAINT AQUA (-1550 9175);
DISPLAY INVISIBLE (-1550 9175);
FORCEPROP 2 LAST $SEC 1
J 0
(-1550 9200);
DISPLAY 0.680851 (-1550 9200);
PAINT MONO (-1550 9200);
DISPLAY INVISIBLE (-1550 9200);
FORCEPROP 2 LAST CDS_SEC 1
J 0
(-1550 9200);
DISPLAY 1.021277 (-1550 9200);
DISPLAY INVISIBLE (-1550 9200);
FORCEADD Q_CAP..1
(-1175 9000);
FORCEPROP 1 LAST PART_NUMBER CH622KMEA03
J 0
(-1125 8825);
DISPLAY 0.617021 (-1125 8825);
PAINT BLUE (-1125 8825);
DISPLAY INVISIBLE (-1125 8825);
FORCEPROP 1 LAST VALUE 22UF
J 0
(-1125 9075);
DISPLAY 0.617021 (-1125 9075);
PAINT SKYBLUE (-1125 9075);
FORCEPROP 1 LAST VOLTAGE 4V
J 0
(-1125 9025);
DISPLAY 0.617021 (-1125 9025);
PAINT SKYBLUE (-1125 9025);
FORCEPROP 1 LAST MATERIAL X6S
J 0
(-1125 8925);
DISPLAY 0.617021 (-1125 8925);
PAINT SKYBLUE (-1125 8925);
FORCEPROP 1 LAST PACK_TYPE C0805
J 0
(-1125 8875);
DISPLAY 0.617021 (-1125 8875);
PAINT SKYBLUE (-1125 8875);
FORCEPROP 1 LAST TOLERANCE 20%
J 0
(-1125 8975);
DISPLAY 0.617021 (-1125 8975);
PAINT SKYBLUE (-1125 8975);
FORCEPROP 1 LAST LOCATION PC437
J 0
(-1125 9125);
DISPLAY 0.617021 (-1125 9125);
PAINT AQUA (-1125 9125);
FORCEPROP 1 LASTPIN (-1175 9100) $PN 1
J 0
(-1165 9080);
DISPLAY 0.617021 (-1165 9080);
PAINT MONO (-1165 9080);
FORCEPROP 1 LASTPIN (-1175 8900) $PN 2
J 0
(-1165 8880);
DISPLAY 0.617021 (-1165 8880);
PAINT MONO (-1165 8880);
FORCEPROP 1 LAST PATH I31
J 0
(-1125 9150);
DISPLAY 0.978723 (-1125 9150);
PAINT WHITE (-1125 9150);
DISPLAY INVISIBLE (-1125 9150);
FORCEPROP 2 LAST CDS_LIB pure_quanta
J 0
(-1175 9000);
DISPLAY INVISIBLE (-1175 9000);
FORCEPROP 1 LAST LOCATION PC437
J 0
(-1125 9175);
DISPLAY 1.021277 (-1125 9175);
PAINT AQUA (-1125 9175);
DISPLAY INVISIBLE (-1125 9175);
FORCEPROP 0 LAST $SEC 1
J 0
(-1125 9175);
DISPLAY 0.680851 (-1125 9175);
PAINT MONO (-1125 9175);
DISPLAY INVISIBLE (-1125 9175);
FORCEPROP 0 LAST CDS_SEC 1
J 0
(-1125 9175);
DISPLAY 1.021277 (-1125 9175);
DISPLAY INVISIBLE (-1125 9175);
FORCEADD Q_CAPP..1
(-775 9000);
FORCEPROP 1 LAST PART_NUMBER CC7560JMD16
J 0
(-725 8825);
DISPLAY 0.617021 (-725 8825);
PAINT BLUE (-725 8825);
DISPLAY INVISIBLE (-725 8825);
FORCEPROP 1 LAST VOLTAGE 2.5V
J 0
(-725 8975);
DISPLAY 0.617021 (-725 8975);
PAINT SKYBLUE (-725 8975);
FORCEPROP 1 LAST MATERIAL OSCON
J 0
(-725 8925);
DISPLAY 0.617021 (-725 8925);
PAINT SKYBLUE (-725 8925);
FORCEPROP 1 LAST TOLERANCE 20%
J 0
(-725 9025);
DISPLAY 0.617021 (-725 9025);
PAINT SKYBLUE (-725 9025);
FORCEPROP 1 LAST VALUE 560UF
J 0
(-725 9075);
DISPLAY 0.617021 (-725 9075);
PAINT SKYBLUE (-725 9075);
FORCEPROP 1 LAST PACK_TYPE THLF
J 0
(-725 8875);
DISPLAY 0.617021 (-725 8875);
PAINT SKYBLUE (-725 8875);
FORCEPROP 1 LAST LOCATION PC2199
J 0
(-725 9125);
DISPLAY 0.617021 (-725 9125);
PAINT AQUA (-725 9125);
FORCEPROP 1 LASTPIN (-775 9100) $PN 1
J 0
(-765 9085);
DISPLAY 0.617021 (-765 9085);
PAINT MONO (-765 9085);
FORCEPROP 1 LASTPIN (-775 8900) $PN 2
J 0
(-765 8885);
DISPLAY 0.617021 (-765 8885);
PAINT MONO (-765 8885);
FORCEPROP 1 LAST PATH I32
J 0
(-725 9150);
DISPLAY 0.978723 (-725 9150);
DISPLAY INVISIBLE (-725 9150);
FORCEPROP 2 LAST CDS_LIB pure_quanta
J 0
(-775 9000);
DISPLAY INVISIBLE (-775 9000);
FORCEPROP 2 LAST $SEC 1
J 0
(-725 9200);
DISPLAY 0.680851 (-725 9200);
PAINT MONO (-725 9200);
DISPLAY INVISIBLE (-725 9200);
FORCEPROP 2 LAST CDS_SEC 1
J 0
(-725 9200);
DISPLAY 1.021277 (-725 9200);
DISPLAY INVISIBLE (-725 9200);
FORCEADD Q_CAPP..1
(-350 9000);
FORCEPROP 1 LAST PART_NUMBER CH733LY8802
J 0
(-300 8825);
DISPLAY 0.617021 (-300 8825);
PAINT BLUE (-300 8825);
DISPLAY INVISIBLE (-300 8825);
FORCEPROP 1 LAST TOLERANCE +10/-35%
J 0
(-300 9025);
DISPLAY 0.617021 (-300 9025);
PAINT SKYBLUE (-300 9025);
FORCEPROP 1 LAST MATERIAL SPCAP
J 0
(-300 8925);
DISPLAY 0.617021 (-300 8925);
PAINT SKYBLUE (-300 8925);
FORCEPROP 1 LAST VALUE 330UF
J 0
(-300 9075);
DISPLAY 0.617021 (-300 9075);
PAINT SKYBLUE (-300 9075);
FORCEPROP 1 LAST PACK_TYPE SMLF
J 0
(-300 8875);
DISPLAY 0.617021 (-300 8875);
PAINT SKYBLUE (-300 8875);
FORCEPROP 1 LAST VOLTAGE 2.5V
J 0
(-300 8975);
DISPLAY 0.617021 (-300 8975);
PAINT SKYBLUE (-300 8975);
FORCEPROP 1 LAST LOCATION PC1930
J 0
(-300 9125);
DISPLAY 0.617021 (-300 9125);
PAINT AQUA (-300 9125);
FORCEPROP 1 LASTPIN (-350 9100) $PN 1
J 0
(-340 9085);
DISPLAY 0.617021 (-340 9085);
FORCEPROP 1 LASTPIN (-350 8900) $PN 2
J 0
(-340 8885);
DISPLAY 0.617021 (-340 8885);
FORCEPROP 1 LAST PATH I33
J 0
(-300 9150);
DISPLAY 0.978723 (-300 9150);
DISPLAY INVISIBLE (-300 9150);
FORCEPROP 2 LAST CDS_LIB pure_quanta
J 0
(-350 9000);
PAINT MONO (-350 9000);
DISPLAY INVISIBLE (-350 9000);
FORCEPROP 2 LAST $SEC 1
J 0
(-300 9200);
DISPLAY 0.680851 (-300 9200);
PAINT MONO (-300 9200);
DISPLAY INVISIBLE (-300 9200);
FORCEPROP 2 LAST CDS_SEC 1
J 0
(-300 9200);
DISPLAY 1.021277 (-300 9200);
DISPLAY INVISIBLE (-300 9200);
FORCEADD UNIVERSAL_GND..1
(-1975 9675);
FORCEPROP 3 LASTPIN (-1975 9725) SIG_NAME GND\g
J 0
(-1965 9735);
DISPLAY 0.659574 (-1965 9735);
PAINT MONO (-1965 9735);
DISPLAY INVISIBLE (-1965 9735);
FORCEPROP 1 LAST PATH I34
J 0
(-1900 9675);
DISPLAY 0.872340 (-1900 9675);
PAINT AQUA (-1900 9675);
DISPLAY INVISIBLE (-1900 9675);
FORCEPROP 2 LAST CDS_LIB logical_power
J 0
(-1975 9675);
PAINT MONO (-1975 9675);
DISPLAY INVISIBLE (-1975 9675);
FORCEPROP 1 LAST HDL_POWER GND
J 1
(-1950 9600);
DISPLAY 0.872340 (-1950 9600);
PAINT GREEN (-1950 9600);
DISPLAY INVISIBLE (-1950 9600);
FORCEADD VCC15..1
(-1975 10475);
FORCEPROP 3 LASTPIN (-1975 10425) SIG_NAME SW_P12V_PVCCINFAON_CPU1_FLT\g
J 0
(-1965 10435);
DISPLAY 0.659574 (-1965 10435);
PAINT MONO (-1965 10435);
DISPLAY INVISIBLE (-1965 10435);
FORCEPROP 1 LAST HDL_POWER SW_P12V_PVCCINFAON_CPU1_FLT
J 1
(-1925 10525);
DISPLAY 0.617021 (-1925 10525);
PAINT GREEN (-1925 10525);
FORCEPROP 1 LAST PATH I35
J 0
(-1925 10500);
DISPLAY 0.872340 (-1925 10500);
PAINT AQUA (-1925 10500);
DISPLAY INVISIBLE (-1925 10500);
FORCEPROP 2 LAST CDS_LIB logical_power
J 0
(-1975 10475);
DISPLAY INVISIBLE (-1975 10475);
FORCEADD UNIVERSAL_GND..1
(125 8625);
FORCEPROP 3 LASTPIN (125 8675) SIG_NAME GND\g
J 0
(135 8685);
DISPLAY 0.659574 (135 8685);
PAINT MONO (135 8685);
DISPLAY INVISIBLE (135 8685);
FORCEPROP 1 LAST PATH I36
J 0
(200 8625);
DISPLAY 0.872340 (200 8625);
PAINT AQUA (200 8625);
DISPLAY INVISIBLE (200 8625);
FORCEPROP 2 LAST CDS_LIB logical_power
J 0
(125 8625);
PAINT MONO (125 8625);
DISPLAY INVISIBLE (125 8625);
FORCEPROP 1 LAST HDL_POWER GND
J 1
(150 8550);
DISPLAY 0.872340 (150 8550);
PAINT GREEN (150 8550);
DISPLAY INVISIBLE (150 8550);
FORCEADD Q_RES..2
(125 9000);
FORCEPROP 1 LAST PART_NUMBER CS14992FB06
J 0
(165 8875);
DISPLAY 0.617021 (165 8875);
PAINT BLUE (165 8875);
DISPLAY INVISIBLE (165 8875);
FORCEPROP 1 LAST VALUE 499
J 0
(170 9075);
DISPLAY 0.617021 (170 9075);
PAINT SKYBLUE (170 9075);
FORCEPROP 1 LAST TOLERANCE 1%
J 0
(170 9025);
DISPLAY 0.617021 (170 9025);
PAINT SKYBLUE (170 9025);
FORCEPROP 1 LAST WATTAGE 1/16W
J 0
(165 8975);
DISPLAY 0.617021 (165 8975);
PAINT SKYBLUE (165 8975);
FORCEPROP 1 LAST MATERIAL CHIP
J 0
(165 8925);
DISPLAY 0.617021 (165 8925);
PAINT SKYBLUE (165 8925);
FORCEPROP 1 LAST PACK_TYPE 0402LF
J 0
(165 8825);
DISPLAY 0.617021 (165 8825);
PAINT SKYBLUE (165 8825);
FORCEPROP 1 LAST LOCATION PR4250
J 0
(170 9125);
DISPLAY 0.617021 (170 9125);
PAINT AQUA (170 9125);
FORCEPROP 1 LASTPIN (125 9100) $PN 1
J 0
(130 9062);
DISPLAY 0.787234 (130 9062);
PAINT MONO (130 9062);
FORCEPROP 1 LASTPIN (125 8900) $PN 2
J 0
(130 8910);
DISPLAY 0.787234 (130 8910);
PAINT MONO (130 8910);
FORCEPROP 1 LAST PATH I37
J 0
(175 9175);
DISPLAY 0.978723 (175 9175);
PAINT WHITE (175 9175);
DISPLAY INVISIBLE (175 9175);
FORCEPROP 2 LAST CDS_LIB pure_quanta
J 0
(125 9000);
DISPLAY INVISIBLE (125 9000);
FORCEPROP 2 LAST BOM_COST VR_PCH
J 0
(175 9175);
DISPLAY 0.680851 (175 9175);
DISPLAY INVISIBLE (175 9175);
FORCEPROP 0 LAST $SEC 1
J 0
(175 9175);
DISPLAY 0.680851 (175 9175);
PAINT MONO (175 9175);
DISPLAY INVISIBLE (175 9175);
FORCEPROP 0 LAST CDS_SEC 1
J 0
(175 9175);
DISPLAY 1.021277 (175 9175);
DISPLAY INVISIBLE (175 9175);
FORCEADD VCC15..1
(125 9350);
FORCEPROP 3 LASTPIN (125 9300) SIG_NAME PVCCFA_EHV_CPU1\g
J 0
(135 9310);
DISPLAY 0.659574 (135 9310);
PAINT MONO (135 9310);
DISPLAY INVISIBLE (135 9310);
FORCEPROP 1 LAST HDL_POWER PVCCFA_EHV_CPU1
J 1
(125 9400);
DISPLAY 0.617021 (125 9400);
PAINT GREEN (125 9400);
FORCEPROP 1 LAST PATH I38
J 0
(175 9375);
DISPLAY 0.872340 (175 9375);
PAINT AQUA (175 9375);
DISPLAY INVISIBLE (175 9375);
FORCEPROP 2 LAST CDS_LIB logical_power
J 0
(125 9350);
DISPLAY INVISIBLE (125 9350);
FORCEADD Q_RES..2
(-6575 10675);
FORCEPROP 1 LAST PART_NUMBER CS00002JB13
J 0
(-6535 10550);
DISPLAY 0.617021 (-6535 10550);
PAINT BLUE (-6535 10550);
DISPLAY INVISIBLE (-6535 10550);
FORCEPROP 1 LAST PACK_TYPE 0402LF
J 0
(-6535 10500);
DISPLAY 0.617021 (-6535 10500);
PAINT SKYBLUE (-6535 10500);
FORCEPROP 1 LAST VALUE 0
J 0
(-6530 10750);
DISPLAY 0.617021 (-6530 10750);
PAINT SKYBLUE (-6530 10750);
FORCEPROP 1 LAST TOLERANCE 5%
J 0
(-6530 10700);
DISPLAY 0.617021 (-6530 10700);
PAINT SKYBLUE (-6530 10700);
FORCEPROP 1 LAST MATERIAL CHIP
J 0
(-6535 10600);
DISPLAY 0.617021 (-6535 10600);
PAINT SKYBLUE (-6535 10600);
FORCEPROP 1 LAST WATTAGE 1/16W
J 0
(-6535 10650);
DISPLAY 0.617021 (-6535 10650);
PAINT SKYBLUE (-6535 10650);
FORCEPROP 1 LAST LOCATION PR678
J 0
(-6530 10800);
DISPLAY 0.617021 (-6530 10800);
PAINT AQUA (-6530 10800);
FORCEPROP 1 LAST PATH I4
J 0
(-6525 10850);
DISPLAY 0.978723 (-6525 10850);
PAINT WHITE (-6525 10850);
DISPLAY INVISIBLE (-6525 10850);
FORCEPROP 2 LAST CDS_LIB pure_quanta
J 0
(-6575 10675);
DISPLAY INVISIBLE (-6575 10675);
FORCEPROP 0 LAST $SEC 1
J 0
(-6525 10850);
DISPLAY INVISIBLE (-6525 10850);
FORCEPROP 0 LAST CDS_SEC 1
J 0
(-6525 10850);
DISPLAY INVISIBLE (-6525 10850);
FORCEPROP 1 LASTPIN (-6575 10775) $PN 1
J 0
(-6570 10737);
DISPLAY 0.787234 (-6570 10737);
PAINT MONO (-6570 10737);
DISPLAY INVISIBLE (-6570 10737);
FORCEPROP 1 LASTPIN (-6575 10575) $PN 2
J 0
(-6570 10585);
DISPLAY 0.787234 (-6570 10585);
PAINT MONO (-6570 10585);
DISPLAY INVISIBLE (-6570 10585);
FORCEADD VCC15..1
(-6575 10900);
FORCEPROP 3 LASTPIN (-6575 10850) SIG_NAME P5V\g
J 0
(-6565 10860);
DISPLAY 0.659574 (-6565 10860);
PAINT MONO (-6565 10860);
DISPLAY INVISIBLE (-6565 10860);
FORCEPROP 1 LAST HDL_POWER P5V
J 1
(-6575 10950);
DISPLAY 0.617021 (-6575 10950);
PAINT GREEN (-6575 10950);
FORCEPROP 1 LAST PATH I5
J 0
(-6525 10925);
DISPLAY 0.872340 (-6525 10925);
PAINT AQUA (-6525 10925);
DISPLAY INVISIBLE (-6525 10925);
FORCEPROP 2 LAST CDS_LIB logical_power
J 0
(-6575 10900);
DISPLAY INVISIBLE (-6575 10900);
FORCEADD OFFPAGE..1
(-6025 8600);
FORCEPROP 2 LAST $XR0 292 
J 0
(-6277 8600);
DISPLAY 0.638298 (-6277 8600);
PAINT MONO (-6277 8600);
FORCEPROP 2 LAST PATH I6
J 0
(-6275 8650);
DISPLAY 1.021277 (-6275 8650);
DISPLAY INVISIBLE (-6275 8650);
FORCEPROP 2 LAST CDS_LIB standard
J 0
(-6025 8600);
DISPLAY INVISIBLE (-6025 8600);
FORCEPROP 1 LAST OFFPAGE TRUE
J 0
(-5700 8475);
DISPLAY 0.872340 (-5700 8475);
PAINT GREEN (-5700 8475);
DISPLAY INVISIBLE (-5700 8475);
FORCEPROP 1 LAST COMMENT_BODY TRUE
J 0
(-5900 8500);
DISPLAY 0.872340 (-5900 8500);
PAINT GREEN (-5900 8500);
DISPLAY INVISIBLE (-5900 8500);
FORCEADD OFFPAGE..5
(-6025 8700);
FORCEPROP 2 LAST $XR0 292 
J 0
(-6310 8700);
DISPLAY 0.638298 (-6310 8700);
PAINT MONO (-6310 8700);
FORCEPROP 2 LAST PATH I7
J 0
(-6300 8750);
DISPLAY 1.021277 (-6300 8750);
DISPLAY INVISIBLE (-6300 8750);
FORCEPROP 2 LAST CDS_LIB standard
J 0
(-6025 8700);
DISPLAY INVISIBLE (-6025 8700);
FORCEPROP 1 LAST OFFPAGE TRUE
J 0
(-5700 8575);
DISPLAY 0.872340 (-5700 8575);
PAINT GREEN (-5700 8575);
DISPLAY INVISIBLE (-5700 8575);
FORCEPROP 1 LAST COMMENT_BODY TRUE
J 0
(-5925 8625);
DISPLAY 0.872340 (-5925 8625);
PAINT GREEN (-5925 8625);
DISPLAY INVISIBLE (-5925 8625);
FORCEADD OFFPAGE..1
(-6025 9100);
FORCEPROP 2 LAST $XR1 293 
J 0
(-6397 9100);
DISPLAY 0.638298 (-6397 9100);
PAINT MONO (-6397 9100);
FORCEPROP 2 LAST $XR0 292 
J 0
(-6277 9100);
DISPLAY 0.638298 (-6277 9100);
PAINT MONO (-6277 9100);
FORCEPROP 2 LAST PATH I8
J 0
(-6275 9150);
DISPLAY 1.021277 (-6275 9150);
DISPLAY INVISIBLE (-6275 9150);
FORCEPROP 2 LAST CDS_LIB standard
J 0
(-6025 9100);
DISPLAY INVISIBLE (-6025 9100);
FORCEPROP 1 LAST OFFPAGE TRUE
J 0
(-5700 8975);
DISPLAY 0.872340 (-5700 8975);
PAINT GREEN (-5700 8975);
DISPLAY INVISIBLE (-5700 8975);
FORCEPROP 1 LAST COMMENT_BODY TRUE
J 0
(-5900 9000);
DISPLAY 0.872340 (-5900 9000);
PAINT GREEN (-5900 9000);
DISPLAY INVISIBLE (-5900 9000);
FORCEADD Q_CAP..2
(-5925 9000);
FORCEPROP 1 LAST PART_NUMBER CH4104K1B00
J 1
(-5650 9050);
DISPLAY 0.617021 (-5650 9050);
PAINT BLUE (-5650 9050);
DISPLAY INVISIBLE (-5650 9050);
FORCEPROP 1 LAST TOLERANCE 10%
J 2
(-5275 9050);
DISPLAY 0.617021 (-5275 9050);
PAINT SKYBLUE (-5275 9050);
FORCEPROP 1 LAST VOLTAGE 25V
J 0
(-5650 9000);
DISPLAY 0.617021 (-5650 9000);
PAINT SKYBLUE (-5650 9000);
FORCEPROP 1 LAST PACK_TYPE 0402
J 1
(-5475 9000);
DISPLAY 0.617021 (-5475 9000);
PAINT SKYBLUE (-5475 9000);
FORCEPROP 1 LAST MATERIAL X7R
J 0
(-5475 9050);
DISPLAY 0.617021 (-5475 9050);
PAINT SKYBLUE (-5475 9050);
FORCEPROP 1 LAST VALUE 0.1UF
J 2
(-5675 9000);
DISPLAY 0.617021 (-5675 9000);
PAINT SKYBLUE (-5675 9000);
FORCEPROP 1 LASTPIN (-6025 9000) $PN 1
J 0
(-6035 9015);
DISPLAY 0.617021 (-6035 9015);
FORCEPROP 1 LASTPIN (-5825 9000) $PN 2
J 0
(-5840 9015);
DISPLAY 0.617021 (-5840 9015);
FORCEPROP 1 LAST LOCATION PC1366
J 1
(-6125 9000);
DISPLAY 0.617021 (-6125 9000);
PAINT AQUA (-6125 9000);
FORCEPROP 1 LAST PATH I9
J 0
(-5925 9200);
DISPLAY 0.978723 (-5925 9200);
PAINT WHITE (-5925 9200);
DISPLAY INVISIBLE (-5925 9200);
FORCEPROP 2 LAST CDS_LIB pure_quanta
J 0
(-5925 9000);
PAINT MONO (-5925 9000);
DISPLAY INVISIBLE (-5925 9000);
FORCEPROP 2 LAST $SEC 1
J 0
(-5925 9250);
DISPLAY 0.680851 (-5925 9250);
PAINT MONO (-5925 9250);
DISPLAY INVISIBLE (-5925 9250);
FORCEPROP 2 LAST CDS_SEC 1
J 0
(-5925 9250);
DISPLAY 1.021277 (-5925 9250);
DISPLAY INVISIBLE (-5925 9250);
FORCEADD QUANTA_TITLE_BLOCK_C..1
(1250 6025);
FORCEPROP 0 LAST CDS_CON_LAST_MODIFIED Fri Aug 25 14:05:05 2023
J 0
(-635 6040);
DISPLAY INVISIBLE (-635 6040);
FORCEPROP 1 LAST CUSTOM_TXT_CDS <CON_LAST_MODIFIED>
J 0
(-635 6040);
DISPLAY 0.978723 (-635 6040);
FORCEPROP 2 LAST CUSTOM_TXT_CDS <XR_PAGE_TITLE>
J 0
(-6640 11275);
DISPLAY 0.638298 (-6640 11275);
PAINT PINK (-6640 11275);
DISPLAY INVISIBLE (-6640 11275);
FORCEPROP 1 LAST CUSTOM_TXT_CDS <NAME_2>
J 0
(-1925 6075);
FORCEPROP 1 LAST CUSTOM_TXT_CDS <NAME_1>
J 0
(-1925 6200);
FORCEPROP 1 LAST CUSTOM_TXT_CDS <Q_NUMBER>
J 0
(-153 6128);
DISPLAY 1.212766 (-153 6128);
FORCEPROP 1 LAST CUSTOM_TXT_CDS <Q_PROJ>
J 0
(-1132 6127);
DISPLAY 1.212766 (-1132 6127);
FORCEPROP 1 LAST CUSTOM_TXT_CDS <Q_REV>
J 0
(1066 6128);
DISPLAY 1.212766 (1066 6128);
FORCEPROP 1 LAST CUSTOM_TXT_CDS <CON_PAGE_NUM> OF <CON_TOTAL_PAGES>
J 0
(804 6043);
DISPLAY 0.978723 (804 6043);
FORCEPROP 1 LAST Q_TITLE VCCFA_EHV_CPU1 VR PHASE (3/3)
J 0
(-8050 6075);
DISPLAY 2.446809 (-8050 6075);
PAINT GREEN (-8050 6075);
FORCEPROP 1 LAST Q_DEPT 
J 1
(-2513 6074);
DISPLAY 1.957447 (-2513 6074);
PAINT GREEN (-2513 6074);
FORCEPROP 2 LAST CDS_XR_PAGE_TITLE CR-294 : @S9S_MB_2U_LIB.S9S_MB_2U(SCH_1):PAGE294
J 0
(-6640 11275);
DISPLAY 0.638298 (-6640 11275);
PAINT PINK (-6640 11275);
DISPLAY INVISIBLE (-6640 11275);
FORCEPROP 1 LAST COMMENT_BODY TRUE
J 0
(1262 6012);
DISPLAY 0.978723 (1262 6012);
PAINT GREEN (1262 6012);
DISPLAY INVISIBLE (1262 6012);
FORCEPROP 2 LAST PAGE_BORDER TRUE
J 0
(-6640 11275);
DISPLAY 0.638298 (-6640 11275);
PAINT PINK (-6640 11275);
DISPLAY INVISIBLE (-6640 11275);
FORCEPROP 1 LAST CDS_LMAN_SYM_OUTLINE -9475,6775,100,-125
J 0
(1250 6025);
DISPLAY 0.468085 (1250 6025);
PAINT GREEN (1250 6025);
DISPLAY INVISIBLE (1250 6025);
FORCEPROP 2 LAST CDS_LIB pure_quanta
J 0
(1250 6025);
DISPLAY INVISIBLE (1250 6025);
FORCEADD DNS..1
(-3100 8675);
PAINT RED (-3100 8675);
FORCEPROP 2 LAST CDS_LIB mstr_misc
J 0
(-3100 8675);
DISPLAY INVISIBLE (-3100 8675);
FORCEPROP 1 LAST COMMENT_BODY TRUE
R 1
J 0
(-3025 8450);
DISPLAY 0.872340 (-3025 8450);
PAINT GREEN (-3025 8450);
DISPLAY INVISIBLE (-3025 8450);
FORCEADD DNS..1
(-5700 10650);
PAINT RED (-5700 10650);
FORCEPROP 2 LAST CDS_LIB mstr_misc
J 0
(-5700 10650);
DISPLAY INVISIBLE (-5700 10650);
FORCEPROP 1 LAST COMMENT_BODY TRUE
R 1
J 0
(-5625 10425);
DISPLAY 0.872340 (-5625 10425);
PAINT GREEN (-5625 10425);
DISPLAY INVISIBLE (-5625 10425);
FORCEADD DNS..1
(-5650 9575);
PAINT RED (-5650 9575);
FORCEPROP 2 LAST CDS_LIB mstr_misc
J 0
(-5650 9575);
DISPLAY INVISIBLE (-5650 9575);
FORCEPROP 1 LAST COMMENT_BODY TRUE
R 1
J 0
(-5575 9350);
DISPLAY 0.872340 (-5575 9350);
PAINT GREEN (-5575 9350);
DISPLAY INVISIBLE (-5575 9350);
FORCEADD DNS..1
(-6775 8575);
PAINT RED (-6775 8575);
FORCEPROP 2 LAST CDS_LIB mstr_misc
J 0
(-6775 8575);
DISPLAY INVISIBLE (-6775 8575);
FORCEPROP 1 LAST COMMENT_BODY TRUE
R 1
J 0
(-6700 8350);
DISPLAY 0.872340 (-6700 8350);
PAINT GREEN (-6700 8350);
DISPLAY INVISIBLE (-6700 8350);
WIRE 16 -1 (125 9300)(125 9200);
WIRE 16 -1 (-1975 10425)(-1975 10350);
WIRE 16 -1 (-2600 9000)(-2600 8900);
WIRE 16 -1 (-5750 10850)(-5750 10775);
WIRE 16 -1 (-6575 10850)(-6575 10775);
WIRE 16 -1 (125 8675)(125 8775);
WIRE 16 -1 (-1975 9725)(-1975 9850);
WIRE 16 -1 (-2525 8600)(-2525 8525);
WIRE 16 -1 (-2525 8650)(-2525 8600);
WIRE 16 -1 (-4175 8600)(-2525 8600);
WIRE 16 -1 (-6100 9550)(-6100 9450);
WIRE 16 -1 (-7025 9000)(-7025 8975);
WIRE 16 -1 (-7025 9000)(-6025 9000);
WIRE 16 -1 (-6775 8500)(-6775 8425);
WIRE 16 -1 (-6775 8700)(-6775 8950);
WIRE 16 -1 (-5025 8950)(-6775 8950);
FORCEPROP 2 LAST SIG_NAME PVCCFA_EHV_CPU1_LSET1
J 0
(-5710 8960);
DISPLAY 0.617021 (-5710 8960);
WIRE 16 -1 (-4175 8650)(-2525 8650);
WIRE 16 -1 (-2525 8750)(-4175 8750);
WIRE 16 -1 (-3025 8700)(-2525 8700);
WIRE 16 -1 (-2525 8650)(-2525 8700);
WIRE 16 -1 (-2525 8700)(-2525 8750);
WIRE 16 -1 (-2925 8900)(-2600 8900);
WIRE 16 -1 (-2575 10000)(-2575 9850);
WIRE 16 -1 (-1975 9850)(-2575 9850);
WIRE 16 -1 (-2950 10000)(-2950 9850);
WIRE 16 -1 (-2950 9850)(-2575 9850);
WIRE 16 -1 (-3325 10000)(-3325 9850);
WIRE 16 -1 (-3325 9850)(-2950 9850);
WIRE 16 -1 (-3775 9850)(-3325 9850);
WIRE 16 -1 (-3775 10000)(-3775 9850);
WIRE 16 -1 (-2575 10200)(-2575 10350);
WIRE 16 -1 (-1975 10350)(-2575 10350);
WIRE 16 -1 (-2950 10350)(-2950 10200);
WIRE 16 -1 (-2950 10350)(-2575 10350);
WIRE 16 -1 (-3325 10200)(-3325 10350);
WIRE 16 -1 (-3325 10350)(-2950 10350);
WIRE 16 -1 (-3775 10200)(-3775 10350);
WIRE 16 -1 (-3775 10350)(-3325 10350);
WIRE 16 -1 (-4000 10350)(-3775 10350);
WIRE 16 -1 (-4000 10350)(-4000 9850);
WIRE 16 -1 (-4175 9850)(-4000 9850);
WIRE 16 -1 (125 8900)(125 8775);
WIRE 16 -1 (-350 8900)(-350 8775);
WIRE 16 -1 (125 8775)(-350 8775);
WIRE 16 -1 (-775 8900)(-775 8775);
WIRE 16 -1 (-350 8775)(-775 8775);
WIRE 16 -1 (-1175 8775)(-1175 8900);
WIRE 16 -1 (-775 8775)(-1175 8775);
WIRE 16 -1 (-1600 8900)(-1600 8775);
WIRE 16 -1 (-1600 8775)(-1175 8775);
WIRE 16 -1 (-2000 8775)(-1600 8775);
WIRE 16 -1 (-2000 8900)(-2000 8775);
WIRE 16 -1 (125 9200)(125 9100);
WIRE 16 -1 (-350 9100)(-350 9200);
WIRE 16 -1 (125 9200)(-350 9200);
WIRE 16 -1 (-775 9100)(-775 9200);
WIRE 16 -1 (-350 9200)(-775 9200);
WIRE 16 -1 (-1175 9200)(-1175 9100);
WIRE 16 -1 (-1175 9200)(-775 9200);
WIRE 16 -1 (-1600 9100)(-1600 9200);
WIRE 16 -1 (-1600 9200)(-1175 9200);
WIRE 16 -1 (-2000 9200)(-2125 9200);
WIRE 16 -1 (-2000 9100)(-2000 9200);
WIRE 16 -1 (-2000 9200)(-1600 9200);
WIRE 16 -1 (-4025 9650)(-3350 9650);
FORCEPROP 0 LAST CDS_PHYS_NET_NAME SW_PVCCFA_EHV_CPU1_BOOT1
J 0
(-3985 9679);
PAINT MONO (-3985 9679);
DISPLAY INVISIBLE (-3985 9679);
WIRE 16 -1 (-4025 9550)(-4025 9650);
FORCEPROP 2 LAST SIG_NAME SW_PVCCFA_EHV_CPU1_BOOT1
J 0
(-4210 9660);
DISPLAY 0.617021 (-4210 9660);
WIRE 16 -1 (-4175 9550)(-4025 9550);
WIRE 16 -1 (-3150 9650)(-2450 9650);
FORCEPROP 2 LAST SIG_NAME SW_PVCCFA_EHV_CPU1_BOOT1_R
J 0
(-2960 9660);
DISPLAY 0.617021 (-2960 9660);
WIRE 16 -1 (-2450 9650)(-2450 9575);
WIRE 16 -1 (-4175 9300)(-2450 9300);
FORCEPROP 0 LAST CDS_PHYS_NET_NAME SW_PVCCFA_EHV_CPU1_BOOTR1
J 0
(-3985 9340);
PAINT MONO (-3985 9340);
DISPLAY INVISIBLE (-3985 9340);
FORCEPROP 2 LAST SIG_NAME SW_PVCCFA_EHV_CPU1_BOOTR1
J 0
(-3985 9310);
DISPLAY 0.617021 (-3985 9310);
WIRE 16 -1 (-2450 9300)(-2450 9375);
WIRE 16 -1 (-4175 8900)(-3125 8900);
FORCEPROP 2 LAST SIG_NAME PVCCFA_EHV_CPU1_NC1
J 0
(-4010 8910);
DISPLAY 0.617021 (-4010 8910);
WIRE 16 -1 (-4175 9200)(-2325 9200);
FORCEPROP 2 LAST SIG_NAME SW_PVCCFA_EHV_CPU1_SW1
J 0
(-3985 9210);
DISPLAY 0.617021 (-3985 9210);
WIRE 16 -1 (-4175 8700)(-3225 8700);
FORCEPROP 2 LAST SIG_NAME PVCCFA_EHV_CPU1_FAULT
J 0
(-4010 8710);
DISPLAY 0.617021 (-4010 8710);
WIRE 16 -1 (-6575 10575)(-6575 10225);
WIRE 16 -1 (-6575 10225)(-6100 10225);
FORCEPROP 2 LAST SIG_NAME PVCCFA_EHV_CPU1_PVCC
J 0
(-6535 10235);
DISPLAY 0.617021 (-6535 10235);
FORCEPROP 2 LASTPROP $XR1 297 
J 0
(-6811 10235);
DISPLAY 0.638298 (-6811 10235);
PAINT MONO (-6811 10235);
FORCEPROP 2 LASTPROP $XR0 293 
J 0
(-6691 10235);
DISPLAY 0.638298 (-6691 10235);
PAINT MONO (-6691 10235);
WIRE 16 -1 (-6100 10225)(-6100 10150);
WIRE 16 -1 (-6100 10225)(-5750 10225);
WIRE 16 -1 (-5750 10575)(-5750 10225);
WIRE 16 -1 (-6100 9850)(-6100 9750);
WIRE 16 -1 (-6100 9950)(-6100 9850);
WIRE 16 -1 (-5650 9850)(-5650 9700);
WIRE 16 -1 (-6100 9850)(-5650 9850);
FORCEPROP 2 LAST SIG_NAME PVCCFA_EHV_CPU1_VDD1
J 0
(-5710 9860);
DISPLAY 0.617021 (-5710 9860);
WIRE 16 -1 (-5650 9850)(-5025 9850);
WIRE 16 -1 (-5025 8700)(-5975 8700);
FORCEPROP 2 LAST SIG_NAME PVCCFA_EHV_CPU1_BTSEN
J 0
(-5710 8710);
DISPLAY 0.617021 (-5710 8710);
WIRE 16 -1 (-5025 8600)(-5975 8600);
FORCEPROP 2 LAST SIG_NAME PVCCFA_EHV_CPU1_BPWM1
J 0
(-5710 8610);
DISPLAY 0.617021 (-5710 8610);
WIRE 16 -1 (-5025 9200)(-5975 9200);
FORCEPROP 2 LAST SIG_NAME PVCCFA_EHV_CPU1_BCSP1
J 0
(-5710 9210);
DISPLAY 0.617021 (-5710 9210);
WIRE 16 -1 (-5025 9350)(-5650 9350);
FORCEPROP 2 LAST SIG_NAME PVCCFA_EHV_CPU1_NC2
J 0
(-5710 9360);
DISPLAY 0.617021 (-5710 9360);
WIRE 16 -1 (-5650 9500)(-5650 9350);
WIRE 16 -1 (-5275 9000)(-5825 9000);
WIRE 16 -1 (-5975 9100)(-5275 9100);
FORCEPROP 2 LAST SIG_NAME PVCCINFAON_CPU1_VREF
J 0
(-5710 9110);
DISPLAY 0.617021 (-5710 9110);
WIRE 16 -1 (-5275 9100)(-5275 9000);
FORCEPROP 0 LAST CDS_PHYS_NET_NAME PVCCINFAON_CPU1_VREF
J 0
(-5275 9025);
PAINT MONO (-5275 9025);
DISPLAY INVISIBLE (-5275 9025);
WIRE 16 -1 (-5275 9100)(-5025 9100);
DOT 1 (125 9200);
DOT 1 (125 8775);
DOT 1 (-350 9200);
DOT 1 (-350 8775);
DOT 1 (-775 9200);
DOT 1 (-775 8775);
DOT 1 (-1175 9200);
DOT 1 (-1600 9200);
DOT 1 (-1175 8775);
DOT 1 (-1600 8775);
DOT 1 (-2000 9200);
DOT 1 (-2575 10350);
DOT 1 (-2575 9850);
DOT 1 (-2950 10350);
DOT 1 (-2950 9850);
DOT 1 (-3325 10350);
DOT 1 (-3325 9850);
DOT 1 (-3775 10350);
DOT 1 (-2525 8700);
DOT 1 (-2525 8650);
DOT 1 (-2525 8600);
DOT 1 (-5650 9850);
DOT 1 (-6100 10225);
DOT 1 (-6100 9850);
DOT 1 (-5275 9100);
FORCENOTE
RENESAS RECOMMEND BLEEDER RESISTOR
(-950 8375) 0;
DISPLAY LEFT (-950 8375);
DISPLAY 1.021277 (-950 8375);
FORCENOTE
(499OHM) TO ABSORB LEAKAGE FROM SPS.
(-950 8300) 0;
DISPLAY LEFT (-950 8300);
DISPLAY 1.021277 (-950 8300);
FORCENOTE
APPLY TO ALL RAILS.
(-950 8225) 0;
DISPLAY LEFT (-950 8225);
DISPLAY 1.021277 (-950 8225);
FORCENOTE
9.6*6.4*9.0
(-1825 9475) 0;
DISPLAY LEFT (-1825 9475);
DISPLAY 0.808511 (-1825 9475);
FORCENOTE
PG1712.301AHLT
(-1825 9550) 0;
DISPLAY LEFT (-1825 9550);
DISPLAY 0.808511 (-1825 9550);
FORCENOTE
DCR = 0.17M OHM
(-1825 9325) 0;
DISPLAY LEFT (-1825 9325);
DISPLAY 0.808511 (-1825 9325);
FORCENOTE
ISAT = 29A @ 125C
(-1825 9400) 0;
DISPLAY LEFT (-1825 9400);
DISPLAY 0.808511 (-1825 9400);
FORCENOTE
PVCCFA_EHV_CPU1
(-4975 10475) 0;
DISPLAY LEFT (-4975 10475);
DISPLAY 1.021277 (-4975 10475);
PAINT WHITE (-4975 10475);
QUIT
